# T6G (Grand Teton) — schematic netlist excerpt (pin names and nets, part order shuffled) for the footprints in the layout excerpt that follows; sources: Cadence DE-HDL packaged netlist, KiCad conversion of 04192023_DAF0TMB3IC0_F0TG_MB_C_brd_V02_OCP.brd

J19  SCONN288_DDR506112002KQ  IO  pkg DDR288S_1-1VXC  page 89
  VIN_BULK0  = P12V_MEM_CPU0
  RFU0  = NC
  VIN_MGMT  = P3V3_AUX
  HSCL  = I3C_SPD_DDRD_CPU0_SCL
  HSDA  = I3C_SPD_DDRD_CPU0_SDA
  VSS0  = GND
  DQ0_A  = M_D_CPU0_SA_DQ<0>
  VSS1  = GND
  DQ1_A  = M_D_CPU0_SA_DQ<1>
  VSS2  = GND
  DQS0_A_T  = M_D_CPU0_SA_DQS_DP<0>
  DQS0_A_C  = M_D_CPU0_SA_DQS_DN<0>
  VSS3  = GND
  DQ4_A  = M_D_CPU0_SA_DQ<4>
  VSS4  = GND
  DQ5_A  = M_D_CPU0_SA_DQ<5>
  VSS5  = GND
  DQ8_A  = M_D_CPU0_SA_DQ<8>
  VSS6  = GND
  DQ9_A  = M_D_CPU0_SA_DQ<9>
  VSS7  = GND
  DQS1_A_T  = M_D_CPU0_SA_DQS_DP<1>
  DQS1_A_C  = M_D_CPU0_SA_DQS_DN<1>
  VSS8  = GND
  DQ12_A  = M_D_CPU0_SA_DQ<12>
  VSS9  = GND
  DQ13_A  = M_D_CPU0_SA_DQ<13>
  VSS10  = GND
  DQ16_A  = M_D_CPU0_SA_DQ<16>
  VSS11  = GND
  DQ17_A  = M_D_CPU0_SA_DQ<17>
  VSS12  = GND
  DQS2_A_T  = M_D_CPU0_SA_DQS_DP<2>
  DQS2_A_C  = M_D_CPU0_SA_DQS_DN<2>
  VSS13  = GND
  DQ20_A  = M_D_CPU0_SA_DQ<20>
  VSS14  = GND
  DQ21_A  = M_D_CPU0_SA_DQ<21>
  VSS15  = GND
  DQ24_A  = M_D_CPU0_SA_DQ<24>
  VSS16  = GND
  DQ25_A  = M_D_CPU0_SA_DQ<25>
  VSS17  = GND
  DQS3_A_T  = M_D_CPU0_SA_DQS_DP<3>
  DQS3_A_C  = M_D_CPU0_SA_DQS_DN<3>
  VSS18  = GND
  DQ28_A  = M_D_CPU0_SA_DQ<28>
  VSS19  = GND
  DQ29_A  = M_D_CPU0_SA_DQ<29>
  VSS20  = GND
  CB0_A  = M_D_CPU0_SA_CB<0>
  VSS21  = GND
  CB1_A  = M_D_CPU0_SA_CB<1>
  VSS22  = GND
  DQS4_A_T  = M_D_CPU0_SA_DQS_DP<4>
  DQS4_A_C  = M_D_CPU0_SA_DQS_DN<4>
  VSS23  = GND
  CB4_A  = M_D_CPU0_SA_CB<4>
  VSS24  = GND
  CB5_A  = M_D_CPU0_SA_CB<5>
  VSS25  = GND
  ALERT_N  = M_D_CPU0_ALERT_N
  VSS26  = GND
  CS0_A_N  = M_D_CPU0_SA_CS_N<0>
  VSS27  = GND
  CA0_A  = M_D_CPU0_SA_CA<0>
  VSS28  = GND
  CA2_A  = M_D_CPU0_SA_CA<2>
  VSS29  = GND
  CA4_A  = M_D_CPU0_SA_CA<4>
  VSS30  = GND
  CA6_A  = M_D_CPU0_SA_CA<6>
  VSS31  = GND
  PAR_A  = M_D_CPU0_SA_PAR
  VSS32  = GND
  CA0_B  = M_D_CPU0_SB_CA<0>
  VSS33  = GND
  CA2_B  = M_D_CPU0_SB_CA<2>
  VSS34  = GND
  CA4_B  = M_D_CPU0_SB_CA<4>
  VSS35  = GND
  CA6_B  = M_D_CPU0_SB_CA<6>
  VSS36  = GND
  CS0_B_N  = M_D_CPU0_SB_CS_N<0>
  VSS37  = GND
  \lbd||rsp_a_n\  = M_D_CPU0_SA_RSP<0>
  \lbs||rsp_b_n\  = M_D_CPU0_SB_RSP<0>
  VSS38  = GND
  CB4_B  = M_D_CPU0_SB_CB<4>
  VSS39  = GND
  CB5_B  = M_D_CPU0_SB_CB<5>
  VSS40  = GND
  \dqs9_b_t||tdqs9_b_t||dbi4_b_n\  = M_D_CPU0_SB_DQS_DP<9>
  \dqs9_b_c||tdqs9_b_c\  = M_D_CPU0_SB_DQS_DN<9>
  VSS41  = GND
  CB0_B  = M_D_CPU0_SB_CB<0>
  VSS42  = GND
  CB1_B  = M_D_CPU0_SB_CB<1>
  VSS43  = GND
  DQ0_B  = M_D_CPU0_SB_DQ<0>
  VSS44  = GND
  DQ1_B  = M_D_CPU0_SB_DQ<1>
  VSS45  = GND
  DQS0_B_T  = M_D_CPU0_SB_DQS_DP<0>
  DQS0_B_C  = M_D_CPU0_SB_DQS_DN<0>
  VSS46  = GND
  DQ4_B  = M_D_CPU0_SB_DQ<4>
  VSS47  = GND
  DQ5_B  = M_D_CPU0_SB_DQ<5>
  VSS48  = GND
  DQ8_B  = M_D_CPU0_SB_DQ<8>
  VSS49  = GND
  DQ9_B  = M_D_CPU0_SB_DQ<9>
  VSS50  = GND
  DQS1_B_T  = M_D_CPU0_SB_DQS_DP<1>
  DQS1_B_C  = M_D_CPU0_SB_DQS_DN<1>
  VSS51  = GND
  DQ12_B  = M_D_CPU0_SB_DQ<12>
  VSS52  = GND
  DQ13_B  = M_D_CPU0_SB_DQ<13>
  VSS53  = GND
  DQ16_B  = M_D_CPU0_SB_DQ<16>
  VSS54  = GND
  DQ17_B  = M_D_CPU0_SB_DQ<17>
  VSS55  = GND
  DQS2_B_T  = M_D_CPU0_SB_DQS_DP<2>
  DQS2_B_C  = M_D_CPU0_SB_DQS_DN<2>
  VSS56  = GND
  DQ20_B  = M_D_CPU0_SB_DQ<20>
  VSS57  = GND
  DQ21_B  = M_D_CPU0_SB_DQ<21>
  VSS58  = GND
  DQ24_B  = M_D_CPU0_SB_DQ<24>
  VSS59  = GND
  DQ25_B  = M_D_CPU0_SB_DQ<25>
  VSS60  = GND
  DQS3_B_T  = M_D_CPU0_SB_DQS_DP<3>
  DQS3_B_C  = M_D_CPU0_SB_DQS_DN<3>
  VSS61  = GND
  DQ28_B  = M_D_CPU0_SB_DQ<28>
  VSS62  = GND
  DQ29_B  = M_D_CPU0_SB_DQ<29>
  VSS63  = GND
  RFU1  = NC
  VIN_BULK1  = P12V_MEM_CPU0
  VIN_BULK2  = P12V_MEM_CPU0
  \pwr_good||fail_n\  = PWRGD_CHD_CPU0_DIMM
  HAS  = PD_CHD_CPU0_DIMM_SAA
  RFU2  = NC
  RFU3  = NC
  VSS64  = GND
  DQ2_A  = M_D_CPU0_SA_DQ<2>
  VSS65  = GND
  DQ3_A  = M_D_CPU0_SA_DQ<3>
  VSS66  = GND
  \dqs5_a_c||tdqs5_a_c||dqs5_a_t||tdqs5_a_t\  = M_D_CPU0_SA_DQS_DN<5>
  \dqs5_a_t||tdqs5_a_t\  = M_D_CPU0_SA_DQS_DP<5>
  VSS67  = GND
  DQ6_A  = M_D_CPU0_SA_DQ<6>
  VSS68  = GND
  DQ7_A  = M_D_CPU0_SA_DQ<7>
  VSS69  = GND
  DQ10_A  = M_D_CPU0_SA_DQ<10>
  VSS70  = GND
  DQ11_A  = M_D_CPU0_SA_DQ<11>
  VSS71  = GND
  \dqs6_a_c||tdqs6_a_c||dqs6_a_t||tdqs6_a_t\  = M_D_CPU0_SA_DQS_DN<6>
  \dqs6_a_t||tdqs6_a_t\  = M_D_CPU0_SA_DQS_DP<6>
  VSS72  = GND
  DQ14_A  = M_D_CPU0_SA_DQ<14>
  VSS73  = GND
  DQ15_A  = M_D_CPU0_SA_DQ<15>
  VSS74  = GND
  DQ18_A  = M_D_CPU0_SA_DQ<18>
  VSS75  = GND
  DQ19_A  = M_D_CPU0_SA_DQ<19>
  VSS76  = GND
  \dqs7_a_c||tdqs7_a_c\  = M_D_CPU0_SA_DQS_DN<7>
  \dqs7_a_t||tdqs7_a_t\  = M_D_CPU0_SA_DQS_DP<7>
  VSS77  = GND
  DQ22_A  = M_D_CPU0_SA_DQ<22>
  VSS78  = GND
  DQ23_A  = M_D_CPU0_SA_DQ<23>
  VSS79  = GND
  DQ26_A  = M_D_CPU0_SA_DQ<26>
  VSS80  = GND
  DQ27_A  = M_D_CPU0_SA_DQ<27>
  VSS81  = GND
  \dqs8_a_c||tdqs8_a_c\  = M_D_CPU0_SA_DQS_DN<8>
  \dqs8_a_t||tdqs8_a_t\  = M_D_CPU0_SA_DQS_DP<8>
  VSS82  = GND
  DQ30_A  = M_D_CPU0_SA_DQ<30>
  VSS83  = GND
  DQ31_A  = M_D_CPU0_SA_DQ<31>
  VSS84  = GND
  CB2_A  = M_D_CPU0_SA_CB<2>
  VSS85  = GND
  CB3_A  = M_D_CPU0_SA_CB<3>
  VSS86  = GND
  \dqs9_a_c||tdqs9_a_c\  = M_D_CPU0_SA_DQS_DN<9>
  \dqs9_a_t||tdqs9_a_t\  = M_D_CPU0_SA_DQS_DP<9>
  VSS87  = GND
  CB6_A  = M_D_CPU0_SA_CB<6>
  VSS88  = GND
  CB7_A  = M_D_CPU0_SA_CB<7>
  VSS89  = GND
  RESET_N  = M_D_CPU0_RESET_N
  VSS90  = GND
  CS1_A_N  = M_D_CPU0_SA_CS_N<1>
  VSS91  = GND
  CA1_A  = M_D_CPU0_SA_CA<1>
  VSS92  = GND
  CA3_A  = M_D_CPU0_SA_CA<3>
  VSS93  = GND
  CA5_A  = M_D_CPU0_SA_CA<5>
  VSS94  = GND
  CK_T  = M_D_CPU0_CLK_DP<0>
  CK_C  = M_D_CPU0_CLK_DN<0>
  VSS95  = GND
  RFU4  = NC
  CA1_B  = M_D_CPU0_SB_CA<1>
  VSS96  = GND
  CA3_B  = M_D_CPU0_SB_CA<3>
  VSS97  = GND
  CA5_B  = M_D_CPU0_SB_CA<5>
  VSS98  = GND
  PAR_B  = M_D_CPU0_SB_PAR
  VSS99  = GND
  CS1_B_N  = M_D_CPU0_SB_CS_N<1>
  VSS100  = GND
  RFU5  = NC
  RFU6  = NC
  VSS101  = GND
  CB6_B  = M_D_CPU0_SB_CB<6>
  VSS102  = GND
  CB7_B  = M_D_CPU0_SB_CB<7>
  VSS103  = GND
  DQS4_B_C  = M_D_CPU0_SB_DQS_DN<4>
  DQS4_B_T  = M_D_CPU0_SB_DQS_DP<4>
  VSS104  = GND
  CB2_B  = M_D_CPU0_SB_CB<2>
  VSS105  = GND
  CB3_B  = M_D_CPU0_SB_CB<3>
  VSS106  = GND
  DQ2_B  = M_D_CPU0_SB_DQ<2>
  VSS107  = GND
  DQ3_B  = M_D_CPU0_SB_DQ<3>
  VSS108  = GND
  \dqs5_b_c||tdqs5_b_c\  = M_D_CPU0_SB_DQS_DN<5>
  \dqs5_b_t||tdqs5_b_t\  = M_D_CPU0_SB_DQS_DP<5>
  VSS109  = GND
  DQ6_B  = M_D_CPU0_SB_DQ<6>
  VSS110  = GND
  DQ7_B  = M_D_CPU0_SB_DQ<7>
  VSS111  = GND
  DQ10_B  = M_D_CPU0_SB_DQ<10>
  VSS112  = GND
  DQ11_B  = M_D_CPU0_SB_DQ<11>
  VSS113  = GND
  \dqs6_b_c||tdqs6_b_c\  = M_D_CPU0_SB_DQS_DN<6>
  \dqs6_b_t||tdqs6_b_t\  = M_D_CPU0_SB_DQS_DP<6>
  VSS114  = GND
  DQ14_B  = M_D_CPU0_SB_DQ<14>
  VSS115  = GND
  DQ15_B  = M_D_CPU0_SB_DQ<15>
  VSS116  = GND
  DQ18_B  = M_D_CPU0_SB_DQ<18>
  VSS117  = GND
  DQ19_B  = M_D_CPU0_SB_DQ<19>
  VSS118  = GND
  \dqs7_b_c||tdqs7_b_c\  = M_D_CPU0_SB_DQS_DN<7>
  \dqs7_b_t||tdqs7_b_t\  = M_D_CPU0_SB_DQS_DP<7>
  VSS119  = GND
  DQ22_B  = M_D_CPU0_SB_DQ<22>
  VSS120  = GND
  DQ23_B  = M_D_CPU0_SB_DQ<23>
  VSS121  = GND
  DQ26_B  = M_D_CPU0_SB_DQ<26>
  VSS122  = GND
  DQ27_B  = M_D_CPU0_SB_DQ<27>
  VSS123  = GND
  \dqs8_b_c||tdqs8_b_c\  = M_D_CPU0_SB_DQS_DN<8>
  \dqs8_b_t||tdqs8_b_t\  = M_D_CPU0_SB_DQS_DP<8>
  VSS124  = GND
  DQ30_B  = M_D_CPU0_SB_DQ<30>
  VSS125  = GND
  DQ31_B  = M_D_CPU0_SB_DQ<31>
  VSS126  = GND
  G1  = GND
  G2  = GND
  G3  = GND

(kicad_pcb
	(version 20260206)
	(generator "pcbnew")
	(generator_version "10.0")
	(general
		(thickness 1.6)
		(legacy_teardrops no)
	)
	(paper "A4")
	(title_block
		(title "04192023_DAF0TMB3IC0_F0TG_MB_C_brd_V02_OCP.brd")
		(comment 1 "Grand Teton / footprint 2350 of 8354 (J19), pads 231-276 of 291")
	)
	(layers
		(0 "F.Cu" signal "TOP")
		(4 "In1.Cu" signal "GND")
		(6 "In2.Cu" signal "IN1")
		(8 "In3.Cu" signal "GND1")
		(10 "In4.Cu" signal "IN2")
		(12 "In5.Cu" signal "GND2")
		(14 "In6.Cu" signal "IN3")
		(16 "In7.Cu" signal "GND3")
		(18 "In8.Cu" signal "VCC")
		(20 "In9.Cu" signal "VCC1")
		(22 "In10.Cu" signal "GND4")
		(24 "In11.Cu" signal "IN4")
		(26 "In12.Cu" signal "GND5")
		(28 "In13.Cu" signal "IN5")
		(30 "In14.Cu" signal "GND6")
		(32 "In15.Cu" signal "IN6")
		(34 "In16.Cu" signal "GND7")
		(2 "B.Cu" signal "BOTTOM")
		(9 "F.Adhes" user "F.Adhesive")
		(11 "B.Adhes" user "B.Adhesive")
		(13 "F.Paste" user "Package Geometry/Pastemask Top")
		(15 "B.Paste" user "Package Geometry/Pastemask Bottom")
		(5 "F.SilkS" user "Ref Des/Silkscreen Top")
		(7 "B.SilkS" user "Ref Des/Silkscreen Bottom")
		(1 "F.Mask" user "Board Geometry/Soldermask Top")
		(3 "B.Mask" user "Board Geometry/Soldermask Bottom")
		(17 "Dwgs.User" user "User.Drawings")
		(19 "Cmts.User" user "User.Comments")
		(21 "Eco1.User" user "User.Eco1")
		(23 "Eco2.User" user "User.Eco2")
		(25 "Edge.Cuts" user "Board Geometry/Outline")
		(27 "Margin" user)
		(31 "F.CrtYd" user "Package Geometry/Place Bound Top")
		(29 "B.CrtYd" user "Package Geometry/Place Bound Bottom")
		(35 "F.Fab" user "Ref Des/Assembly Top")
		(33 "B.Fab" user "Ref Des/Assembly Bottom")
	)
	(footprint ""
		(layer "F.Cu")
		(at 282.685998 -255.560068 180)
		(property "Reference" "J19"
			(at -2.2098 -81.984088 0)
			(unlocked yes)
			(layer "F.SilkS")
			(effects
				(font
					(size 0.7874 0.5842)
					(thickness 0.1524)
				)
			)
		)
		(property "Value" ""
			(at 0 0 180)
			(layer "F.Fab")
			(effects
				(font
					(size 1.27 1.27)
				)
			)
		)
		(duplicate_pad_numbers_are_jumpers no)
		(pad "231" smd rect
			(at 2.050034 14.875002 90)
			(size 0.519938 1.4986)
			(layers "F.Cu" "F.Mask" "F.Paste")
			(net "Net_2296")
		)
		(pad "232" smd rect
			(at 2.050034 15.724886 90)
			(size 0.519938 1.4986)
			(layers "F.Cu" "F.Mask" "F.Paste")
			(net "Net_2297")
		)
		(pad "233" smd rect
			(at 2.050034 16.575024 90)
			(size 0.519938 1.4986)
			(layers "F.Cu" "F.Mask" "F.Paste")
			(net "GND")
		)
		(pad "234" smd rect
			(at 2.050034 17.424908 90)
			(size 0.519938 1.4986)
			(layers "F.Cu" "F.Mask" "F.Paste")
			(net "M_D_CPU0_SB_CB<6>")
		)
		(pad "235" smd rect
			(at 2.050034 18.275046 90)
			(size 0.519938 1.4986)
			(layers "F.Cu" "F.Mask" "F.Paste")
			(net "GND")
		)
		(pad "236" smd rect
			(at 2.050034 19.12493 90)
			(size 0.519938 1.4986)
			(layers "F.Cu" "F.Mask" "F.Paste")
			(net "M_D_CPU0_SB_CB<7>")
		)
		(pad "237" smd rect
			(at 2.050034 19.975068 90)
			(size 0.519938 1.4986)
			(layers "F.Cu" "F.Mask" "F.Paste")
			(net "GND")
		)
		(pad "238" smd rect
			(at 2.050034 20.824952 90)
			(size 0.519938 1.4986)
			(layers "F.Cu" "F.Mask" "F.Paste")
			(net "M_D_CPU0_SB_DQS_DN<4>")
		)
		(pad "239" smd rect
			(at 2.050034 21.67509 90)
			(size 0.519938 1.4986)
			(layers "F.Cu" "F.Mask" "F.Paste")
			(net "M_D_CPU0_SB_DQS_DP<4>")
		)
		(pad "240" smd rect
			(at 2.050034 22.524974 90)
			(size 0.519938 1.4986)
			(layers "F.Cu" "F.Mask" "F.Paste")
			(net "GND")
		)
		(pad "241" smd rect
			(at 2.050034 23.375112 90)
			(size 0.519938 1.4986)
			(layers "F.Cu" "F.Mask" "F.Paste")
			(net "M_D_CPU0_SB_CB<2>")
		)
		(pad "242" smd rect
			(at 2.050034 24.224996 90)
			(size 0.519938 1.4986)
			(layers "F.Cu" "F.Mask" "F.Paste")
			(net "GND")
		)
		(pad "243" smd rect
			(at 2.050034 25.07488 90)
			(size 0.519938 1.4986)
			(layers "F.Cu" "F.Mask" "F.Paste")
			(net "M_D_CPU0_SB_CB<3>")
		)
		(pad "244" smd rect
			(at 2.050034 25.925018 90)
			(size 0.519938 1.4986)
			(layers "F.Cu" "F.Mask" "F.Paste")
			(net "GND")
		)
		(pad "245" smd rect
			(at 2.050034 26.774902 90)
			(size 0.519938 1.4986)
			(layers "F.Cu" "F.Mask" "F.Paste")
			(net "M_D_CPU0_SB_DQ<2>")
		)
		(pad "246" smd rect
			(at 2.050034 27.62504 90)
			(size 0.519938 1.4986)
			(layers "F.Cu" "F.Mask" "F.Paste")
			(net "GND")
		)
		(pad "247" smd rect
			(at 2.050034 28.474924 90)
			(size 0.519938 1.4986)
			(layers "F.Cu" "F.Mask" "F.Paste")
			(net "M_D_CPU0_SB_DQ<3>")
		)
		(pad "248" smd rect
			(at 2.050034 29.325062 90)
			(size 0.519938 1.4986)
			(layers "F.Cu" "F.Mask" "F.Paste")
			(net "GND")
		)
		(pad "249" smd rect
			(at 2.050034 30.174946 90)
			(size 0.519938 1.4986)
			(layers "F.Cu" "F.Mask" "F.Paste")
			(net "M_D_CPU0_SB_DQS_DN<5>")
		)
		(pad "250" smd rect
			(at 2.050034 31.025084 90)
			(size 0.519938 1.4986)
			(layers "F.Cu" "F.Mask" "F.Paste")
			(net "M_D_CPU0_SB_DQS_DP<5>")
		)
		(pad "251" smd rect
			(at 2.050034 31.874968 90)
			(size 0.519938 1.4986)
			(layers "F.Cu" "F.Mask" "F.Paste")
			(net "GND")
		)
		(pad "252" smd rect
			(at 2.050034 32.725106 90)
			(size 0.519938 1.4986)
			(layers "F.Cu" "F.Mask" "F.Paste")
			(net "M_D_CPU0_SB_DQ<6>")
		)
		(pad "253" smd rect
			(at 2.050034 33.57499 90)
			(size 0.519938 1.4986)
			(layers "F.Cu" "F.Mask" "F.Paste")
			(net "GND")
		)
		(pad "254" smd rect
			(at 2.050034 34.425128 90)
			(size 0.519938 1.4986)
			(layers "F.Cu" "F.Mask" "F.Paste")
			(net "M_D_CPU0_SB_DQ<7>")
		)
		(pad "255" smd rect
			(at 2.050034 35.275012 90)
			(size 0.519938 1.4986)
			(layers "F.Cu" "F.Mask" "F.Paste")
			(net "GND")
		)
		(pad "256" smd rect
			(at 2.050034 36.124896 90)
			(size 0.519938 1.4986)
			(layers "F.Cu" "F.Mask" "F.Paste")
			(net "M_D_CPU0_SB_DQ<10>")
		)
		(pad "257" smd rect
			(at 2.050034 36.975034 90)
			(size 0.519938 1.4986)
			(layers "F.Cu" "F.Mask" "F.Paste")
			(net "GND")
		)
		(pad "258" smd rect
			(at 2.050034 37.824918 90)
			(size 0.519938 1.4986)
			(layers "F.Cu" "F.Mask" "F.Paste")
			(net "M_D_CPU0_SB_DQ<11>")
		)
		(pad "259" smd rect
			(at 2.050034 38.675056 90)
			(size 0.519938 1.4986)
			(layers "F.Cu" "F.Mask" "F.Paste")
			(net "GND")
		)
		(pad "260" smd rect
			(at 2.050034 39.52494 90)
			(size 0.519938 1.4986)
			(layers "F.Cu" "F.Mask" "F.Paste")
			(net "M_D_CPU0_SB_DQS_DN<6>")
		)
		(pad "261" smd rect
			(at 2.050034 40.375078 90)
			(size 0.519938 1.4986)
			(layers "F.Cu" "F.Mask" "F.Paste")
			(net "M_D_CPU0_SB_DQS_DP<6>")
		)
		(pad "262" smd rect
			(at 2.050034 41.224962 90)
			(size 0.519938 1.4986)
			(layers "F.Cu" "F.Mask" "F.Paste")
			(net "GND")
		)
		(pad "263" smd rect
			(at 2.050034 42.0751 90)
			(size 0.519938 1.4986)
			(layers "F.Cu" "F.Mask" "F.Paste")
			(net "M_D_CPU0_SB_DQ<14>")
		)
		(pad "264" smd rect
			(at 2.050034 42.924984 90)
			(size 0.519938 1.4986)
			(layers "F.Cu" "F.Mask" "F.Paste")
			(net "GND")
		)
		(pad "265" smd rect
			(at 2.050034 43.775122 90)
			(size 0.519938 1.4986)
			(layers "F.Cu" "F.Mask" "F.Paste")
			(net "M_D_CPU0_SB_DQ<15>")
		)
		(pad "266" smd rect
			(at 2.050034 44.625006 90)
			(size 0.519938 1.4986)
			(layers "F.Cu" "F.Mask" "F.Paste")
			(net "GND")
		)
		(pad "267" smd rect
			(at 2.050034 45.47489 90)
			(size 0.519938 1.4986)
			(layers "F.Cu" "F.Mask" "F.Paste")
			(net "M_D_CPU0_SB_DQ<18>")
		)
		(pad "268" smd rect
			(at 2.050034 46.325028 90)
			(size 0.519938 1.4986)
			(layers "F.Cu" "F.Mask" "F.Paste")
			(net "GND")
		)
		(pad "269" smd rect
			(at 2.050034 47.174912 90)
			(size 0.519938 1.4986)
			(layers "F.Cu" "F.Mask" "F.Paste")
			(net "M_D_CPU0_SB_DQ<19>")
		)
		(pad "270" smd rect
			(at 2.050034 48.02505 90)
			(size 0.519938 1.4986)
			(layers "F.Cu" "F.Mask" "F.Paste")
			(net "GND")
		)
		(pad "271" smd rect
			(at 2.050034 48.874934 90)
			(size 0.519938 1.4986)
			(layers "F.Cu" "F.Mask" "F.Paste")
			(net "M_D_CPU0_SB_DQS_DN<7>")
		)
		(pad "272" smd rect
			(at 2.050034 49.725072 90)
			(size 0.519938 1.4986)
			(layers "F.Cu" "F.Mask" "F.Paste")
			(net "M_D_CPU0_SB_DQS_DP<7>")
		)
		(pad "273" smd rect
			(at 2.050034 50.574956 90)
			(size 0.519938 1.4986)
			(layers "F.Cu" "F.Mask" "F.Paste")
			(net "GND")
		)
		(pad "274" smd rect
			(at 2.050034 51.425094 90)
			(size 0.519938 1.4986)
			(layers "F.Cu" "F.Mask" "F.Paste")
			(net "M_D_CPU0_SB_DQ<22>")
		)
		(pad "275" smd rect
			(at 2.050034 52.274978 90)
			(size 0.519938 1.4986)
			(layers "F.Cu" "F.Mask" "F.Paste")
			(net "GND")
		)
		(pad "276" smd rect
			(at 2.050034 53.125116 90)
			(size 0.519938 1.4986)
			(layers "F.Cu" "F.Mask" "F.Paste")
			(net "M_D_CPU0_SB_DQ<23>")
		)
	)
)
